(kicad_pcb
	(version 20241229)
	(generator "pcbnew")
	(generator_version "9.0")
	(general
		(thickness 1.62)
		(legacy_teardrops no)
	)
	(paper "A3")
	(title_block
		(title "COM Express 7 Baseboard")
		(date "2025-02-04")
		(rev "1.1.2")
		(company "Antmicro Ltd")
		(comment 1 "www.antmicro.com")
		(comment 9 "footprints 362-365 of 802")
	)
	(layers
		(0 "F.Cu" signal)
		(4 "In1.Cu" signal)
		(6 "In2.Cu" signal)
		(8 "In3.Cu" signal)
		(10 "In4.Cu" signal)
		(12 "In5.Cu" signal)
		(14 "In6.Cu" signal)
		(2 "B.Cu" signal)
		(9 "F.Adhes" user "F.Adhesive")
		(11 "B.Adhes" user "B.Adhesive")
		(13 "F.Paste" user)
		(15 "B.Paste" user)
		(5 "F.SilkS" user "F.Silkscreen")
		(7 "B.SilkS" user "B.Silkscreen")
		(1 "F.Mask" user)
		(3 "B.Mask" user)
		(17 "Dwgs.User" user "User.Drawings")
		(19 "Cmts.User" user "User.Comments")
		(21 "Eco1.User" user "User.Eco1")
		(23 "Eco2.User" user "User.Eco2")
		(25 "Edge.Cuts" user)
		(27 "Margin" user)
		(31 "F.CrtYd" user "F.Courtyard")
		(29 "B.CrtYd" user "B.Courtyard")
		(35 "F.Fab" user)
		(33 "B.Fab" user)
	)
	(footprint "antmicro-footprints:R_0402_1005Metric"
		(layer "F.Cu")
		(at 120.2 86.36 -90)
		(descr "Resistor SMD 0402")
		(tags "resistor SMD 0402")
		(property "Reference" "R12"
			(at 0.8 -0.4 90)
			(layer "F.SilkS")
			(effects
				(font
					(size 0.7 0.7)
					(thickness 0.15)
				)
				(justify right bottom)
			)
		)
		(property "Value" "R_2k2_0402"
			(at -1.011843 1.772047 90)
			(layer "F.Fab")
			(effects
				(font
					(size 0.7 0.7)
					(thickness 0.15)
				)
				(justify right bottom)
			)
		)
		(property "Datasheet" "https://www.bourns.com/docs/product-datasheets/cr.pdf"
			(at 0 0 270)
			(layer "F.Fab")
			(hide yes)
			(effects
				(font
					(size 1.27 1.27)
					(thickness 0.15)
				)
			)
		)
		(property "Author" "Antmicro"
			(at 33.84 206.56 0)
			(layer "F.Fab")
			(hide yes)
			(effects
				(font
					(size 1 1)
					(thickness 0.15)
				)
			)
		)
		(property "License" "Apache-2.0"
			(at 33.84 206.56 0)
			(layer "F.Fab")
			(hide yes)
			(effects
				(font
					(size 1 1)
					(thickness 0.15)
				)
			)
		)
		(property "MPN" "CR0402-FX-2201GLF"
			(at 33.84 206.56 0)
			(layer "F.Fab")
			(hide yes)
			(effects
				(font
					(size 1 1)
					(thickness 0.15)
				)
			)
		)
		(property "Manufacturer" "Bourns"
			(at 33.84 206.56 0)
			(layer "F.Fab")
			(hide yes)
			(effects
				(font
					(size 1 1)
					(thickness 0.15)
				)
			)
		)
		(property "Public" "False"
			(at 33.84 206.56 0)
			(layer "F.Fab")
			(hide yes)
			(effects
				(font
					(size 1 1)
					(thickness 0.15)
				)
			)
		)
		(property "Tolerance" "1%"
			(at 33.84 206.56 0)
			(layer "F.Fab")
			(hide yes)
			(effects
				(font
					(size 1 1)
					(thickness 0.15)
				)
			)
		)
		(property "Val" "2k2"
			(at 33.84 206.56 0)
			(layer "F.Fab")
			(hide yes)
			(effects
				(font
					(size 1 1)
					(thickness 0.15)
				)
			)
		)
		(sheetname "2xUSB3.0+RJ45")
		(sheetfile "usb3+rj45.kicad_sch")
		(attr smd)
		(fp_rect
			(start -0.925 -0.47)
			(end 0.925 0.47)
			(stroke
				(width 0.05)
				(type default)
			)
			(fill no)
			(layer "F.CrtYd")
		)
		(fp_rect
			(start -0.5 -0.25)
			(end 0.5 0.25)
			(stroke
				(width 0.15)
				(type solid)
			)
			(fill no)
			(layer "F.Fab")
		)
		(pad "1" smd roundrect
			(at -0.48 0 270)
			(size 0.59 0.64)
			(layers "F.Cu" "F.Mask" "F.Paste")
			(roundrect_rratio 0.25)
			(net 1 "GND")
			(pintype "passive")
			(teardrops
				(best_length_ratio 0.2)
				(max_length 1)
				(best_width_ratio 0.9)
				(max_width 2)
				(curved_edges yes)
				(filter_ratio 0.9)
				(enabled yes)
				(allow_two_segments yes)
				(prefer_zone_connections yes)
			)
		)
		(pad "2" smd roundrect
			(at 0.48 0 270)
			(size 0.59 0.64)
			(layers "F.Cu" "F.Mask" "F.Paste")
			(roundrect_rratio 0.25)
			(net 547 "/2xUSB3.0+RJ45/P1_ISET")
			(pintype "passive")
			(teardrops
				(best_length_ratio 0.2)
				(max_length 1)
				(best_width_ratio 0.9)
				(max_width 2)
				(curved_edges yes)
				(filter_ratio 0.9)
				(enabled yes)
				(allow_two_segments yes)
				(prefer_zone_connections yes)
			)
		)
	)
	(footprint "antmicro-footprints:C_0402_1005Metric"
		(layer "F.Cu")
		(at 304.14 127.79)
		(descr "Capacitor SMD 0402")
		(tags "capacitor SMD 0402")
		(property "Reference" "C53"
			(at 0.86 0.42 0)
			(layer "F.SilkS")
			(effects
				(font
					(size 0.7 0.7)
					(thickness 0.15)
				)
				(justify left bottom)
			)
		)
		(property "Value" "C_100n_0402"
			(at -1.022927 2.155213 0)
			(layer "F.Fab")
			(effects
				(font
					(size 0.7 0.7)
					(thickness 0.15)
				)
				(justify left bottom)
			)
		)
		(property "Datasheet" "https://www.murata.com/products/productdetail?partno=GRM155R61H104KE14%23"
			(at 0 0 0)
			(layer "F.Fab")
			(hide yes)
			(effects
				(font
					(size 1.27 1.27)
					(thickness 0.15)
				)
			)
		)
		(property "Author" "Antmicro"
			(at 0 0 0)
			(layer "F.Fab")
			(hide yes)
			(effects
				(font
					(size 1 1)
					(thickness 0.15)
				)
			)
		)
		(property "Dielectric" "X5R"
			(at 0 0 0)
			(layer "F.Fab")
			(hide yes)
			(effects
				(font
					(size 1 1)
					(thickness 0.15)
				)
			)
		)
		(property "License" "Apache-2.0"
			(at 0 0 0)
			(layer "F.Fab")
			(hide yes)
			(effects
				(font
					(size 1 1)
					(thickness 0.15)
				)
			)
		)
		(property "MPN" "GRM155R61H104KE14D"
			(at 0 0 0)
			(layer "F.Fab")
			(hide yes)
			(effects
				(font
					(size 1 1)
					(thickness 0.15)
				)
			)
		)
		(property "Manufacturer" "Murata"
			(at 0 0 0)
			(layer "F.Fab")
			(hide yes)
			(effects
				(font
					(size 1 1)
					(thickness 0.15)
				)
			)
		)
		(property "Public" "False"
			(at 0 0 0)
			(layer "F.Fab")
			(hide yes)
			(effects
				(font
					(size 1 1)
					(thickness 0.15)
				)
			)
		)
		(property "Val" "100n"
			(at 0 0 0)
			(layer "F.Fab")
			(hide yes)
			(effects
				(font
					(size 1 1)
					(thickness 0.15)
				)
			)
		)
		(property "Voltage" "50V"
			(at 0 0 0)
			(layer "F.Fab")
			(hide yes)
			(effects
				(font
					(size 1 1)
					(thickness 0.15)
				)
			)
		)
		(sheetname "Power")
		(sheetfile "power.kicad_sch")
		(attr smd)
		(fp_rect
			(start -0.925 -0.47)
			(end 0.925 0.47)
			(stroke
				(width 0.05)
				(type default)
			)
			(fill no)
			(layer "F.CrtYd")
		)
		(fp_line
			(start -0.494 -0.25)
			(end 0.504 -0.25)
			(stroke
				(width 0.15)
				(type solid)
			)
			(layer "F.Fab")
		)
		(fp_line
			(start -0.494 0.248)
			(end -0.494 -0.25)
			(stroke
				(width 0.15)
				(type solid)
			)
			(layer "F.Fab")
		)
		(fp_line
			(start 0.504 -0.25)
			(end 0.504 0.248)
			(stroke
				(width 0.15)
				(type solid)
			)
			(layer "F.Fab")
		)
		(fp_line
			(start 0.504 0.248)
			(end -0.494 0.248)
			(stroke
				(width 0.15)
				(type solid)
			)
			(layer "F.Fab")
		)
		(pad "1" smd roundrect
			(at -0.48 0)
			(size 0.59 0.64)
			(layers "F.Cu" "F.Mask" "F.Paste")
			(roundrect_rratio 0.25)
			(net 1 "GND")
			(pintype "passive")
			(teardrops
				(best_length_ratio 0.2)
				(max_length 1)
				(best_width_ratio 0.9)
				(max_width 2)
				(curved_edges yes)
				(filter_ratio 0.9)
				(enabled yes)
				(allow_two_segments yes)
				(prefer_zone_connections yes)
			)
		)
		(pad "2" smd roundrect
			(at 0.48 0)
			(size 0.59 0.64)
			(layers "F.Cu" "F.Mask" "F.Paste")
			(roundrect_rratio 0.25)
			(net 72 "Net-(U20-CT)")
			(pintype "passive")
			(teardrops
				(best_length_ratio 0.2)
				(max_length 1)
				(best_width_ratio 0.9)
				(max_width 2)
				(curved_edges yes)
				(filter_ratio 0.9)
				(enabled yes)
				(allow_two_segments yes)
				(prefer_zone_connections yes)
			)
		)
	)
	(footprint "antmicro-footprints:USON-10_2.5x1mm_P0.5mm"
		(layer "F.Cu")
		(at 97.502 151.085 90)
		(descr "USON-10 2.5x1mm_ Pitch 0.5mm")
		(tags "USON-10 2.5x1mm Pitch 0.5mm")
		(property "Reference" "U8"
			(at -0.415 3.098 0)
			(layer "F.SilkS")
			(effects
				(font
					(size 0.7 0.7)
					(thickness 0.15)
				)
				(justify right bottom)
			)
		)
		(property "Value" "ESD204DQAR"
			(at 0.018 2.499 90)
			(layer "F.Fab")
			(effects
				(font
					(size 0.7 0.7)
					(thickness 0.15)
				)
				(justify left top)
			)
		)
		(property "Datasheet" "https://www.ti.com/lit/ds/symlink/esd204.pdf?ts=1706004844383&ref_url=https%253A%252F%252Fwww.ti.com%252Finterface%252Fdiodes%252Fesd-protection-diodes%252Fproducts.html"
			(at 0 0 90)
			(layer "F.Fab")
			(hide yes)
			(effects
				(font
					(size 1.27 1.27)
					(thickness 0.15)
				)
			)
		)
		(property "Author" "Antmicro"
			(at -42.04 261.9 0)
			(layer "F.Fab")
			(hide yes)
			(effects
				(font
					(size 1 1)
					(thickness 0.15)
				)
			)
		)
		(property "License" "Apache-2.0"
			(at -42.04 261.9 0)
			(layer "F.Fab")
			(hide yes)
			(effects
				(font
					(size 1 1)
					(thickness 0.15)
				)
			)
		)
		(property "MPN" "ESD204DQAR"
			(at -42.04 261.9 0)
			(layer "F.Fab")
			(hide yes)
			(effects
				(font
					(size 1 1)
					(thickness 0.15)
				)
			)
		)
		(property "Manufacturer" "Texas Instruments"
			(at -42.04 261.9 0)
			(layer "F.Fab")
			(hide yes)
			(effects
				(font
					(size 1 1)
					(thickness 0.15)
				)
			)
		)
		(sheetname "OCuLink")
		(sheetfile "oculink.kicad_sch")
		(attr smd)
		(fp_line
			(start 0.498 -1.401)
			(end -0.5 -1.401)
			(stroke
				(width 0.15)
				(type solid)
			)
			(layer "F.SilkS")
		)
		(fp_line
			(start 0.498 1.398)
			(end -0.5 1.398)
			(stroke
				(width 0.15)
				(type solid)
			)
			(layer "F.SilkS")
		)
		(fp_circle
			(center -0.68 -1.27)
			(end -0.63 -1.27)
			(stroke
				(width 0.15)
				(type solid)
			)
			(fill yes)
			(layer "F.SilkS")
		)
		(fp_rect
			(start -0.8 -1.5)
			(end 0.8 1.499)
			(stroke
				(width 0.05)
				(type solid)
			)
			(fill no)
			(layer "F.CrtYd")
		)
		(fp_line
			(start 0.498 -1.25)
			(end -0.25 -1.25)
			(stroke
				(width 0.15)
				(type solid)
			)
			(layer "F.Fab")
		)
		(fp_line
			(start 0.498 -1.25)
			(end 0.498 1.249)
			(stroke
				(width 0.15)
				(type solid)
			)
			(layer "F.Fab")
		)
		(fp_line
			(start -0.25 -1.25)
			(end -0.5 -1)
			(stroke
				(width 0.15)
				(type solid)
			)
			(layer "F.Fab")
		)
		(fp_line
			(start -0.5 -1)
			(end -0.5 1.249)
			(stroke
				(width 0.15)
				(type solid)
			)
			(layer "F.Fab")
		)
		(fp_line
			(start -0.5 1.249)
			(end 0.498 1.249)
			(stroke
				(width 0.15)
				(type solid)
			)
			(layer "F.Fab")
		)
		(pad "1" smd roundrect
			(at -0.387 -1)
			(size 0.25 0.55)
			(layers "F.Cu" "F.Mask" "F.Paste")
			(roundrect_rratio 0.25)
			(net 186 "/OCuLink/PCIe_{x4}.RX0+")
			(pintype "passive")
			(teardrops
				(best_length_ratio 0.2)
				(max_length 1)
				(best_width_ratio 0.9)
				(max_width 2)
				(curved_edges yes)
				(filter_ratio 0.9)
				(enabled yes)
				(allow_two_segments yes)
				(prefer_zone_connections yes)
			)
		)
		(pad "2" smd roundrect
			(at -0.387 -0.5)
			(size 0.25 0.55)
			(layers "F.Cu" "F.Mask" "F.Paste")
			(roundrect_rratio 0.25)
			(net 187 "/OCuLink/PCIe_{x4}.RX0-")
			(pintype "passive")
			(teardrops
				(best_length_ratio 0.2)
				(max_length 1)
				(best_width_ratio 0.9)
				(max_width 2)
				(curved_edges yes)
				(filter_ratio 0.9)
				(enabled yes)
				(allow_two_segments yes)
				(prefer_zone_connections yes)
			)
		)
		(pad "3" smd roundrect
			(at -0.387 0)
			(size 0.4 0.55)
			(layers "F.Cu" "F.Mask" "F.Paste")
			(roundrect_rratio 0.25)
			(net 1 "GND")
			(pintype "power_in")
			(teardrops
				(best_length_ratio 0.2)
				(max_length 1)
				(best_width_ratio 0.9)
				(max_width 2)
				(curved_edges yes)
				(filter_ratio 0.9)
				(enabled yes)
				(allow_two_segments yes)
				(prefer_zone_connections yes)
			)
		)
		(pad "4" smd roundrect
			(at -0.387 0.498)
			(size 0.25 0.55)
			(layers "F.Cu" "F.Mask" "F.Paste")
			(roundrect_rratio 0.25)
			(net 188 "/OCuLink/PCIe_{x4}.RX1+")
			(pintype "passive")
			(teardrops
				(best_length_ratio 0.2)
				(max_length 1)
				(best_width_ratio 0.9)
				(max_width 2)
				(curved_edges yes)
				(filter_ratio 0.9)
				(enabled yes)
				(allow_two_segments yes)
				(prefer_zone_connections yes)
			)
		)
		(pad "5" smd roundrect
			(at -0.387 0.998)
			(size 0.25 0.55)
			(layers "F.Cu" "F.Mask" "F.Paste")
			(roundrect_rratio 0.25)
			(net 189 "/OCuLink/PCIe_{x4}.RX1-")
			(pintype "passive")
			(teardrops
				(best_length_ratio 0.2)
				(max_length 1)
				(best_width_ratio 0.9)
				(max_width 2)
				(curved_edges yes)
				(filter_ratio 0.9)
				(enabled yes)
				(allow_two_segments yes)
				(prefer_zone_connections yes)
			)
		)
		(pad "6" smd roundrect
			(at 0.385 0.998)
			(size 0.25 0.55)
			(layers "F.Cu" "F.Mask" "F.Paste")
			(roundrect_rratio 0.25)
			(net 189 "/OCuLink/PCIe_{x4}.RX1-")
			(pintype "passive")
			(teardrops
				(best_length_ratio 0.2)
				(max_length 1)
				(best_width_ratio 0.9)
				(max_width 2)
				(curved_edges yes)
				(filter_ratio 0.9)
				(enabled yes)
				(allow_two_segments yes)
				(prefer_zone_connections yes)
			)
		)
		(pad "7" smd roundrect
			(at 0.385 0.498)
			(size 0.25 0.55)
			(layers "F.Cu" "F.Mask" "F.Paste")
			(roundrect_rratio 0.25)
			(net 188 "/OCuLink/PCIe_{x4}.RX1+")
			(pintype "passive")
			(teardrops
				(best_length_ratio 0.2)
				(max_length 1)
				(best_width_ratio 0.9)
				(max_width 2)
				(curved_edges yes)
				(filter_ratio 0.9)
				(enabled yes)
				(allow_two_segments yes)
				(prefer_zone_connections yes)
			)
		)
		(pad "8" smd roundrect
			(at 0.385 0)
			(size 0.4 0.55)
			(layers "F.Cu" "F.Mask" "F.Paste")
			(roundrect_rratio 0.25)
			(net 1 "GND")
			(pintype "passive")
			(teardrops
				(best_length_ratio 0.2)
				(max_length 1)
				(best_width_ratio 0.9)
				(max_width 2)
				(curved_edges yes)
				(filter_ratio 0.9)
				(enabled yes)
				(allow_two_segments yes)
				(prefer_zone_connections yes)
			)
		)
		(pad "9" smd roundrect
			(at 0.385 -0.5)
			(size 0.25 0.55)
			(layers "F.Cu" "F.Mask" "F.Paste")
			(roundrect_rratio 0.25)
			(net 187 "/OCuLink/PCIe_{x4}.RX0-")
			(pintype "passive")
			(teardrops
				(best_length_ratio 0.2)
				(max_length 1)
				(best_width_ratio 0.9)
				(max_width 2)
				(curved_edges yes)
				(filter_ratio 0.9)
				(enabled yes)
				(allow_two_segments yes)
				(prefer_zone_connections yes)
			)
		)
		(pad "10" smd roundrect
			(at 0.385 -1)
			(size 0.25 0.55)
			(layers "F.Cu" "F.Mask" "F.Paste")
			(roundrect_rratio 0.25)
			(net 186 "/OCuLink/PCIe_{x4}.RX0+")
			(pintype "passive")
			(teardrops
				(best_length_ratio 0.2)
				(max_length 1)
				(best_width_ratio 0.9)
				(max_width 2)
				(curved_edges yes)
				(filter_ratio 0.9)
				(enabled yes)
				(allow_two_segments yes)
				(prefer_zone_connections yes)
			)
		)
	)
	(footprint "antmicro-footprints:R_0402_1005Metric"
		(layer "F.Cu")
		(at 308.694999 121.61 180)
		(descr "Resistor SMD 0402")
		(tags "resistor SMD 0402")
		(property "Reference" "R97"
			(at -1.055001 -1.4 0)
			(layer "F.SilkS")
			(effects
				(font
					(size 0.7 0.7)
					(thickness 0.15)
				)
				(justify right bottom)
			)
		)
		(property "Value" "R_10k_0402"
			(at -1.011843 1.772047 0)
			(layer "F.Fab")
			(effects
				(font
					(size 0.7 0.7)
					(thickness 0.15)
				)
				(justify right bottom)
			)
		)
		(property "Datasheet" "https://www.bourns.com/docs/product-datasheets/cr.pdf"
			(at 0 0 180)
			(layer "F.Fab")
			(hide yes)
			(effects
				(font
					(size 1.27 1.27)
					(thickness 0.15)
				)
			)
		)
		(property "Author" "Antmicro"
			(at 617.389998 243.22 0)
			(layer "F.Fab")
			(hide yes)
			(effects
				(font
					(size 1 1)
					(thickness 0.15)
				)
			)
		)
		(property "License" "Apache-2.0"
			(at 617.389998 243.22 0)
			(layer "F.Fab")
			(hide yes)
			(effects
				(font
					(size 1 1)
					(thickness 0.15)
				)
			)
		)
		(property "MPN" "CR0402-FX-1002GLF"
			(at 617.389998 243.22 0)
			(layer "F.Fab")
			(hide yes)
			(effects
				(font
					(size 1 1)
					(thickness 0.15)
				)
			)
		)
		(property "Manufacturer" "Bourns"
			(at 617.389998 243.22 0)
			(layer "F.Fab")
			(hide yes)
			(effects
				(font
					(size 1 1)
					(thickness 0.15)
				)
			)
		)
		(property "Public" "False"
			(at 617.389998 243.22 0)
			(layer "F.Fab")
			(hide yes)
			(effects
				(font
					(size 1 1)
					(thickness 0.15)
				)
			)
		)
		(property "Tolerance" "1%"
			(at 617.389998 243.22 0)
			(layer "F.Fab")
			(hide yes)
			(effects
				(font
					(size 1 1)
					(thickness 0.15)
				)
			)
		)
		(property "Val" "10k"
			(at 617.389998 243.22 0)
			(layer "F.Fab")
			(hide yes)
			(effects
				(font
					(size 1 1)
					(thickness 0.15)
				)
			)
		)
		(sheetname "Power")
		(sheetfile "power.kicad_sch")
		(attr smd)
		(fp_rect
			(start -0.925 -0.47)
			(end 0.925 0.47)
			(stroke
				(width 0.05)
				(type default)
			)
			(fill no)
			(layer "F.CrtYd")
		)
		(fp_rect
			(start -0.5 -0.25)
			(end 0.5 0.25)
			(stroke
				(width 0.15)
				(type solid)
			)
			(fill no)
			(layer "F.Fab")
		)
		(pad "1" smd roundrect
			(at -0.48 0 180)
			(size 0.59 0.64)
			(layers "F.Cu" "F.Mask" "F.Paste")
			(roundrect_rratio 0.25)
			(net 580 "Net-(U18-FB)")
			(pintype "passive")
			(teardrops
				(best_length_ratio 0.2)
				(max_length 1)
				(best_width_ratio 0.9)
				(max_width 2)
				(curved_edges yes)
				(filter_ratio 0.9)
				(enabled yes)
				(allow_two_segments yes)
				(prefer_zone_connections yes)
			)
		)
		(pad "2" smd roundrect
			(at 0.48 0 180)
			(size 0.59 0.64)
			(layers "F.Cu" "F.Mask" "F.Paste")
			(roundrect_rratio 0.25)
			(net 70 "Net-(C49-Pad2)")
			(pintype "passive")
			(teardrops
				(best_length_ratio 0.2)
				(max_length 1)
				(best_width_ratio 0.9)
				(max_width 2)
				(curved_edges yes)
				(filter_ratio 0.9)
				(enabled yes)
				(allow_two_segments yes)
				(prefer_zone_connections yes)
			)
		)
	)
)
